# BARRELEYE-G2-SXM2 RISER BOARD-EVT-X00-BOM-X01-20171102_Final.xls.xlsx — DEPOP_GA (bom)
| FOXCONN TECHNOLOGY GROUP |  |  |  |  |  |  |  |  |  |  |  |  |
| BILL OF MATERIAL |  |  |  |  |  |  |  |  |  |  |  |  |
| REV OF  BOM |  | CUSTOMER | <name> |  | CUSTOMER P/N |  | PRODUCT CODE |  | PWA  REV |  | DATE |  |
| Sourcing (Single/Sole/Multi) | Critical Commodity (Y or N) | Component Class (1, 2, other) | Customer PSL (Y or N) | Item Number | Foxconn P/N | Customer P/N | Part Description | Manufacturer  Full Name | Manufacturer  Part Number | Qty | RoHS Status | Location |
